(kicad_pcb
	(version 20260206)
	(generator "pcbnew")
	(generator_version "10.0")
	(general
		(thickness 1.6)
		(legacy_teardrops no)
	)
	(paper "A4")
	(title_block
		(title "Wiwynn_Tioga_Pass_MB.brd")
		(comment 1 "Tioga Pass / footprints 3441-3447 of 4770")
	)
	(layers
		(0 "F.Cu" signal "TOP")
		(4 "In1.Cu" signal "L2GND")
		(6 "In2.Cu" signal "L3")
		(8 "In3.Cu" signal "L4GND")
		(10 "In4.Cu" signal "L5")
		(12 "In5.Cu" signal "L6GND")
		(14 "In6.Cu" signal "L7VCC")
		(16 "In7.Cu" signal "L8VCC")
		(18 "In8.Cu" signal "L9GND")
		(20 "In9.Cu" signal "L10")
		(22 "In10.Cu" signal "L11GND")
		(24 "In11.Cu" signal "L12")
		(26 "In12.Cu" signal "L13GND")
		(2 "B.Cu" signal "BOTTOM")
		(9 "F.Adhes" user "F.Adhesive")
		(11 "B.Adhes" user "B.Adhesive")
		(13 "F.Paste" user "Package Geometry/Pastemask Top")
		(15 "B.Paste" user "Package Geometry/Pastemask Bottom")
		(5 "F.SilkS" user "Ref Des/Silkscreen Top")
		(7 "B.SilkS" user "Ref Des/Silkscreen Bottom")
		(1 "F.Mask" user "Board Geometry/Soldermask Top")
		(3 "B.Mask" user "Board Geometry/Soldermask Bottom")
		(17 "Dwgs.User" user "User.Drawings")
		(19 "Cmts.User" user "User.Comments")
		(21 "Eco1.User" user "User.Eco1")
		(23 "Eco2.User" user "User.Eco2")
		(25 "Edge.Cuts" user "Board Geometry/Outline")
		(27 "Margin" user)
		(31 "F.CrtYd" user "Package Geometry/Place Bound Top")
		(29 "B.CrtYd" user "Package Geometry/Place Bound Bottom")
		(35 "F.Fab" user "Ref Des/Assembly Top")
		(33 "B.Fab" user "Ref Des/Assembly Bottom")
	)
	(footprint ""
		(layer "B.Cu")
		(at 214.581232 -98.1202)
		(property "Reference" "R6N4"
			(at 0 0 0)
			(layer "B.SilkS")
			(hide yes)
			(effects
				(font
					(size 1.27 1.27)
				)
				(justify mirror)
			)
		)
		(property "Value" ""
			(at 0 0 0)
			(layer "B.Fab")
			(effects
				(font
					(size 1.27 1.27)
				)
				(justify mirror)
			)
		)
		(duplicate_pad_numbers_are_jumpers no)
		(fp_poly
			(pts
				(xy 0.2794 -0.1016) (xy -0.2794 -0.1016) (xy -0.2794 0.9906) (xy 0.2794 0.9906)
			)
			(stroke
				(width 0)
				(type default)
			)
			(fill no)
			(layer "B.CrtYd")
		)
		(fp_line
			(start -0.2794 -0.1016)
			(end 0.2794 -0.1016)
			(stroke
				(width 0.1)
				(type default)
			)
			(layer "B.Fab")
		)
		(fp_line
			(start -0.2794 0.9906)
			(end -0.2794 -0.1016)
			(stroke
				(width 0.1)
				(type default)
			)
			(layer "B.Fab")
		)
		(fp_line
			(start 0.2794 -0.1016)
			(end 0.2794 0.9906)
			(stroke
				(width 0.1)
				(type default)
			)
			(layer "B.Fab")
		)
		(fp_line
			(start 0.2794 0.9906)
			(end -0.2794 0.9906)
			(stroke
				(width 0.1)
				(type default)
			)
			(layer "B.Fab")
		)
		(pad "1" smd rect
			(at 0 0 180)
			(size 0.508 0.508)
			(layers "B.Cu" "B.Mask" "B.Paste")
			(net "PVSA_CPU0")
		)
		(pad "2" smd rect
			(at 0 0.889 180)
			(size 0.508 0.508)
			(layers "B.Cu" "B.Mask" "B.Paste")
			(net "GND")
		)
		(zone
			(layer "B.Cu")
			(hatch none 0.5)
			(connect_pads
				(clearance 0)
			)
			(min_thickness 0.25)
			(keepout
				(tracks allowed)
				(vias not_allowed)
				(pads allowed)
				(copperpour not_allowed)
				(footprints allowed)
			)
			(placement
				(enabled no)
				(sheetname "")
			)
			(fill
				(thermal_gap 0.5)
				(thermal_bridge_width 0.5)
				(island_removal_mode 0)
			)
			(polygon
				(pts
					(xy 214.835232 -97.8662) (xy 214.327232 -97.8662) (xy 214.327232 -97.4852) (xy 214.835232 -97.4852)
				)
			)
		)
		(zone
			(layer "B.Cu")
			(hatch none 0.5)
			(connect_pads
				(clearance 0)
			)
			(min_thickness 0.25)
			(keepout
				(tracks not_allowed)
				(vias allowed)
				(pads allowed)
				(copperpour not_allowed)
				(footprints allowed)
			)
			(placement
				(enabled no)
				(sheetname "")
			)
			(fill
				(thermal_gap 0.5)
				(thermal_bridge_width 0.5)
				(island_removal_mode 0)
			)
			(polygon
				(pts
					(xy 214.835232 -97.4852) (xy 214.327232 -97.4852) (xy 214.327232 -97.8662) (xy 214.835232 -97.8662)
				)
			)
		)
	)
	(footprint ""
		(layer "B.Cu")
		(at 317.72606 -125.42774 180)
		(property "Reference" "R3R8"
			(at 0 0 0)
			(layer "B.SilkS")
			(hide yes)
			(effects
				(font
					(size 1.27 1.27)
				)
				(justify mirror)
			)
		)
		(property "Value" ""
			(at 0 0 0)
			(layer "B.Fab")
			(effects
				(font
					(size 1.27 1.27)
				)
				(justify mirror)
			)
		)
		(duplicate_pad_numbers_are_jumpers no)
		(fp_poly
			(pts
				(xy 0.2794 -0.1016) (xy -0.2794 -0.1016) (xy -0.2794 0.9906) (xy 0.2794 0.9906)
			)
			(stroke
				(width 0)
				(type default)
			)
			(fill no)
			(layer "B.CrtYd")
		)
		(fp_line
			(start 0.2794 0.9906)
			(end -0.2794 0.9906)
			(stroke
				(width 0.1)
				(type default)
			)
			(layer "B.Fab")
		)
		(fp_line
			(start 0.2794 -0.1016)
			(end 0.2794 0.9906)
			(stroke
				(width 0.1)
				(type default)
			)
			(layer "B.Fab")
		)
		(fp_line
			(start -0.2794 0.9906)
			(end -0.2794 -0.1016)
			(stroke
				(width 0.1)
				(type default)
			)
			(layer "B.Fab")
		)
		(fp_line
			(start -0.2794 -0.1016)
			(end 0.2794 -0.1016)
			(stroke
				(width 0.1)
				(type default)
			)
			(layer "B.Fab")
		)
		(pad "1" smd rect
			(at 0 0)
			(size 0.508 0.508)
			(layers "B.Cu" "B.Mask" "B.Paste")
			(net "SMB_DDR_DEF_VPP_SCL_R")
		)
		(pad "2" smd rect
			(at 0 0.889)
			(size 0.508 0.508)
			(layers "B.Cu" "B.Mask" "B.Paste")
			(net "SMB_DDR_DEF_VPP_SCL")
		)
		(zone
			(layer "B.Cu")
			(hatch none 0.5)
			(connect_pads
				(clearance 0)
			)
			(min_thickness 0.25)
			(keepout
				(tracks not_allowed)
				(vias allowed)
				(pads allowed)
				(copperpour not_allowed)
				(footprints allowed)
			)
			(placement
				(enabled no)
				(sheetname "")
			)
			(fill
				(thermal_gap 0.5)
				(thermal_bridge_width 0.5)
				(island_removal_mode 0)
			)
			(polygon
				(pts
					(xy 317.47206 -126.06274) (xy 317.98006 -126.06274) (xy 317.98006 -125.68174) (xy 317.47206 -125.68174)
				)
			)
		)
		(zone
			(layer "B.Cu")
			(hatch none 0.5)
			(connect_pads
				(clearance 0)
			)
			(min_thickness 0.25)
			(keepout
				(tracks allowed)
				(vias not_allowed)
				(pads allowed)
				(copperpour not_allowed)
				(footprints allowed)
			)
			(placement
				(enabled no)
				(sheetname "")
			)
			(fill
				(thermal_gap 0.5)
				(thermal_bridge_width 0.5)
				(island_removal_mode 0)
			)
			(polygon
				(pts
					(xy 317.47206 -125.68174) (xy 317.98006 -125.68174) (xy 317.98006 -126.06274) (xy 317.47206 -126.06274)
				)
			)
		)
	)
	(footprint ""
		(layer "B.Cu")
		(at 382.782826 -72.058276 -90)
		(property "Reference" "R7E19"
			(at 0 0 90)
			(layer "B.SilkS")
			(hide yes)
			(effects
				(font
					(size 1.27 1.27)
				)
				(justify mirror)
			)
		)
		(property "Value" ""
			(at 0 0 90)
			(layer "B.Fab")
			(effects
				(font
					(size 1.27 1.27)
				)
				(justify mirror)
			)
		)
		(duplicate_pad_numbers_are_jumpers no)
		(fp_poly
			(pts
				(xy 0.2794 -0.1016) (xy -0.2794 -0.1016) (xy -0.2794 0.9906) (xy 0.2794 0.9906)
			)
			(stroke
				(width 0)
				(type default)
			)
			(fill no)
			(layer "B.CrtYd")
		)
		(fp_line
			(start -0.2794 0.9906)
			(end -0.2794 -0.1016)
			(stroke
				(width 0.1)
				(type default)
			)
			(layer "B.Fab")
		)
		(fp_line
			(start 0.2794 0.9906)
			(end -0.2794 0.9906)
			(stroke
				(width 0.1)
				(type default)
			)
			(layer "B.Fab")
		)
		(fp_line
			(start -0.2794 -0.1016)
			(end 0.2794 -0.1016)
			(stroke
				(width 0.1)
				(type default)
			)
			(layer "B.Fab")
		)
		(fp_line
			(start 0.2794 -0.1016)
			(end 0.2794 0.9906)
			(stroke
				(width 0.1)
				(type default)
			)
			(layer "B.Fab")
		)
		(pad "1" smd rect
			(at 0 0 90)
			(size 0.508 0.508)
			(layers "B.Cu" "B.Mask" "B.Paste")
			(net "P3V3_STBY")
		)
		(pad "2" smd rect
			(at 0 0.889 90)
			(size 0.508 0.508)
			(layers "B.Cu" "B.Mask" "B.Paste")
			(net "FM_MEM_EVENT_FUNC")
		)
		(zone
			(layer "B.Cu")
			(hatch none 0.5)
			(connect_pads
				(clearance 0)
			)
			(min_thickness 0.25)
			(keepout
				(tracks not_allowed)
				(vias allowed)
				(pads allowed)
				(copperpour not_allowed)
				(footprints allowed)
			)
			(placement
				(enabled no)
				(sheetname "")
			)
			(fill
				(thermal_gap 0.5)
				(thermal_bridge_width 0.5)
				(island_removal_mode 0)
			)
			(polygon
				(pts
					(xy 382.147826 -71.804276) (xy 382.147826 -72.312276) (xy 382.528826 -72.312276) (xy 382.528826 -71.804276)
				)
			)
		)
		(zone
			(layer "B.Cu")
			(hatch none 0.5)
			(connect_pads
				(clearance 0)
			)
			(min_thickness 0.25)
			(keepout
				(tracks allowed)
				(vias not_allowed)
				(pads allowed)
				(copperpour not_allowed)
				(footprints allowed)
			)
			(placement
				(enabled no)
				(sheetname "")
			)
			(fill
				(thermal_gap 0.5)
				(thermal_bridge_width 0.5)
				(island_removal_mode 0)
			)
			(polygon
				(pts
					(xy 382.528826 -71.804276) (xy 382.528826 -72.312276) (xy 382.147826 -72.312276) (xy 382.147826 -71.804276)
				)
			)
		)
	)
	(footprint ""
		(layer "B.Cu")
		(at 173.863 -80.645 -90)
		(property "Reference" "C6P11"
			(at 0 0 90)
			(layer "B.SilkS")
			(hide yes)
			(effects
				(font
					(size 1.27 1.27)
				)
				(justify mirror)
			)
		)
		(property "Value" ""
			(at 0 0 90)
			(layer "B.Fab")
			(effects
				(font
					(size 1.27 1.27)
				)
				(justify mirror)
			)
		)
		(duplicate_pad_numbers_are_jumpers no)
		(fp_poly
			(pts
				(xy -0.3048 -0.1016) (xy -0.3048 0.9906) (xy 0.3048 0.9906) (xy 0.3048 -0.1016)
			)
			(stroke
				(width 0)
				(type default)
			)
			(fill no)
			(layer "B.CrtYd")
		)
		(fp_line
			(start -0.3048 0.9906)
			(end -0.3048 -0.1016)
			(stroke
				(width 0.1)
				(type default)
			)
			(layer "B.Fab")
		)
		(fp_line
			(start 0.3048 0.9906)
			(end -0.3048 0.9906)
			(stroke
				(width 0.1)
				(type default)
			)
			(layer "B.Fab")
		)
		(fp_line
			(start -0.3048 -0.1016)
			(end 0.3048 -0.1016)
			(stroke
				(width 0.1)
				(type default)
			)
			(layer "B.Fab")
		)
		(fp_line
			(start 0.3048 -0.1016)
			(end 0.3048 0.9906)
			(stroke
				(width 0.1)
				(type default)
			)
			(layer "B.Fab")
		)
		(pad "1" smd rect
			(at 0 0 90)
			(size 0.508 0.508)
			(layers "B.Cu" "B.Mask" "B.Paste")
			(net "P3V3_DB1200")
		)
		(pad "2" smd rect
			(at 0 0.889 90)
			(size 0.508 0.508)
			(layers "B.Cu" "B.Mask" "B.Paste")
			(net "GND")
		)
		(zone
			(layer "B.Cu")
			(hatch none 0.5)
			(connect_pads
				(clearance 0)
			)
			(min_thickness 0.25)
			(keepout
				(tracks not_allowed)
				(vias allowed)
				(pads allowed)
				(copperpour not_allowed)
				(footprints allowed)
			)
			(placement
				(enabled no)
				(sheetname "")
			)
			(fill
				(thermal_gap 0.5)
				(thermal_bridge_width 0.5)
				(island_removal_mode 0)
			)
			(polygon
				(pts
					(xy 173.228 -80.391) (xy 173.228 -80.899) (xy 173.609 -80.899) (xy 173.609 -80.391)
				)
			)
		)
		(zone
			(layer "B.Cu")
			(hatch none 0.5)
			(connect_pads
				(clearance 0)
			)
			(min_thickness 0.25)
			(keepout
				(tracks allowed)
				(vias not_allowed)
				(pads allowed)
				(copperpour not_allowed)
				(footprints allowed)
			)
			(placement
				(enabled no)
				(sheetname "")
			)
			(fill
				(thermal_gap 0.5)
				(thermal_bridge_width 0.5)
				(island_removal_mode 0)
			)
			(polygon
				(pts
					(xy 173.609 -80.391) (xy 173.609 -80.899) (xy 173.228 -80.899) (xy 173.228 -80.391)
				)
			)
		)
	)
	(footprint ""
		(layer "B.Cu")
		(at 489.65739 -147.193 90)
		(property "Reference" "R1L14"
			(at 0 0 90)
			(layer "B.SilkS")
			(hide yes)
			(effects
				(font
					(size 1.27 1.27)
				)
				(justify mirror)
			)
		)
		(property "Value" ""
			(at 0 0 90)
			(layer "B.Fab")
			(effects
				(font
					(size 1.27 1.27)
				)
				(justify mirror)
			)
		)
		(duplicate_pad_numbers_are_jumpers no)
		(fp_poly
			(pts
				(xy 0.2794 -0.1016) (xy -0.2794 -0.1016) (xy -0.2794 0.9906) (xy 0.2794 0.9906)
			)
			(stroke
				(width 0)
				(type default)
			)
			(fill no)
			(layer "B.CrtYd")
		)
		(fp_line
			(start 0.2794 -0.1016)
			(end 0.2794 0.9906)
			(stroke
				(width 0.1)
				(type default)
			)
			(layer "B.Fab")
		)
		(fp_line
			(start -0.2794 -0.1016)
			(end 0.2794 -0.1016)
			(stroke
				(width 0.1)
				(type default)
			)
			(layer "B.Fab")
		)
		(fp_line
			(start 0.2794 0.9906)
			(end -0.2794 0.9906)
			(stroke
				(width 0.1)
				(type default)
			)
			(layer "B.Fab")
		)
		(fp_line
			(start -0.2794 0.9906)
			(end -0.2794 -0.1016)
			(stroke
				(width 0.1)
				(type default)
			)
			(layer "B.Fab")
		)
		(pad "1" smd rect
			(at 0 0 270)
			(size 0.508 0.508)
			(layers "B.Cu" "B.Mask" "B.Paste")
			(net "LED_POSTCODE_6")
		)
		(pad "2" smd rect
			(at 0 0.889 270)
			(size 0.508 0.508)
			(layers "B.Cu" "B.Mask" "B.Paste")
			(net "LED_POSTCODE_6_R")
		)
		(zone
			(layer "B.Cu")
			(hatch none 0.5)
			(connect_pads
				(clearance 0)
			)
			(min_thickness 0.25)
			(keepout
				(tracks allowed)
				(vias not_allowed)
				(pads allowed)
				(copperpour not_allowed)
				(footprints allowed)
			)
			(placement
				(enabled no)
				(sheetname "")
			)
			(fill
				(thermal_gap 0.5)
				(thermal_bridge_width 0.5)
				(island_removal_mode 0)
			)
			(polygon
				(pts
					(xy 489.91139 -147.447) (xy 489.91139 -146.939) (xy 490.29239 -146.939) (xy 490.29239 -147.447)
				)
			)
		)
		(zone
			(layer "B.Cu")
			(hatch none 0.5)
			(connect_pads
				(clearance 0)
			)
			(min_thickness 0.25)
			(keepout
				(tracks not_allowed)
				(vias allowed)
				(pads allowed)
				(copperpour not_allowed)
				(footprints allowed)
			)
			(placement
				(enabled no)
				(sheetname "")
			)
			(fill
				(thermal_gap 0.5)
				(thermal_bridge_width 0.5)
				(island_removal_mode 0)
			)
			(polygon
				(pts
					(xy 490.29239 -147.447) (xy 490.29239 -146.939) (xy 489.91139 -146.939) (xy 489.91139 -147.447)
				)
			)
		)
	)
	(footprint ""
		(layer "B.Cu")
		(at 400.43608 -141.224 180)
		(property "Reference" "C7B16"
			(at 0 0 0)
			(layer "B.SilkS")
			(hide yes)
			(effects
				(font
					(size 1.27 1.27)
				)
				(justify mirror)
			)
		)
		(property "Value" ""
			(at 0 0 0)
			(layer "B.Fab")
			(effects
				(font
					(size 1.27 1.27)
				)
				(justify mirror)
			)
		)
		(duplicate_pad_numbers_are_jumpers no)
		(fp_rect
			(start 0.4953 1.6002)
			(end -0.4953 -0.2032)
			(stroke
				(width 0)
				(type default)
			)
			(fill no)
			(layer "B.CrtYd")
		)
		(fp_line
			(start 0.4953 1.6002)
			(end 0.4953 -0.2032)
			(stroke
				(width 0.1)
				(type default)
			)
			(layer "B.Fab")
		)
		(fp_line
			(start 0.4953 -0.2032)
			(end -0.4953 -0.2032)
			(stroke
				(width 0.1)
				(type default)
			)
			(layer "B.Fab")
		)
		(fp_line
			(start -0.4953 1.6002)
			(end 0.4953 1.6002)
			(stroke
				(width 0.1)
				(type default)
			)
			(layer "B.Fab")
		)
		(fp_line
			(start -0.4953 -0.2032)
			(end -0.4953 1.6002)
			(stroke
				(width 0.1)
				(type default)
			)
			(layer "B.Fab")
		)
		(pad "1" smd rect
			(at 0 0)
			(size 0.762 0.889)
			(layers "B.Cu" "B.Mask" "B.Paste")
			(net "P1V05_PCH_STBY")
		)
		(pad "2" smd rect
			(at 0 1.397)
			(size 0.762 0.889)
			(layers "B.Cu" "B.Mask" "B.Paste")
			(net "GND")
		)
		(zone
			(layer "B.Cu")
			(hatch none 0.5)
			(connect_pads
				(clearance 0)
			)
			(min_thickness 0.25)
			(keepout
				(tracks not_allowed)
				(vias allowed)
				(pads allowed)
				(copperpour not_allowed)
				(footprints allowed)
			)
			(placement
				(enabled no)
				(sheetname "")
			)
			(fill
				(thermal_gap 0.5)
				(thermal_bridge_width 0.5)
				(island_removal_mode 0)
			)
			(polygon
				(pts
					(xy 400.05508 -142.1765) (xy 400.05508 -141.6685) (xy 400.81708 -141.6685) (xy 400.81708 -142.1765)
				)
			)
		)
	)
	(footprint ""
		(layer "B.Cu")
		(at 117.221 -77.978 -90)
		(property "Reference" "R7P10"
			(at 0 0 90)
			(layer "B.SilkS")
			(hide yes)
			(effects
				(font
					(size 1.27 1.27)
				)
				(justify mirror)
			)
		)
		(property "Value" ""
			(at 0 0 90)
			(layer "B.Fab")
			(effects
				(font
					(size 1.27 1.27)
				)
				(justify mirror)
			)
		)
		(duplicate_pad_numbers_are_jumpers no)
		(fp_poly
			(pts
				(xy 0.2794 -0.1016) (xy -0.2794 -0.1016) (xy -0.2794 0.9906) (xy 0.2794 0.9906)
			)
			(stroke
				(width 0)
				(type default)
			)
			(fill no)
			(layer "B.CrtYd")
		)
		(fp_line
			(start -0.2794 0.9906)
			(end -0.2794 -0.1016)
			(stroke
				(width 0.1)
				(type default)
			)
			(layer "B.Fab")
		)
		(fp_line
			(start 0.2794 0.9906)
			(end -0.2794 0.9906)
			(stroke
				(width 0.1)
				(type default)
			)
			(layer "B.Fab")
		)
		(fp_line
			(start -0.2794 -0.1016)
			(end 0.2794 -0.1016)
			(stroke
				(width 0.1)
				(type default)
			)
			(layer "B.Fab")
		)
		(fp_line
			(start 0.2794 -0.1016)
			(end 0.2794 0.9906)
			(stroke
				(width 0.1)
				(type default)
			)
			(layer "B.Fab")
		)
		(pad "1" smd rect
			(at 0 0 90)
			(size 0.508 0.508)
			(layers "B.Cu" "B.Mask" "B.Paste")
			(net "A_CPU1_PE012_RBIAS")
		)
		(pad "2" smd rect
			(at 0 0.889 90)
			(size 0.508 0.508)
			(layers "B.Cu" "B.Mask" "B.Paste")
			(net "GND")
		)
		(zone
			(layer "B.Cu")
			(hatch none 0.5)
			(connect_pads
				(clearance 0)
			)
			(min_thickness 0.25)
			(keepout
				(tracks not_allowed)
				(vias allowed)
				(pads allowed)
				(copperpour not_allowed)
				(footprints allowed)
			)
			(placement
				(enabled no)
				(sheetname "")
			)
			(fill
				(thermal_gap 0.5)
				(thermal_bridge_width 0.5)
				(island_removal_mode 0)
			)
			(polygon
				(pts
					(xy 116.586 -77.724) (xy 116.586 -78.232) (xy 116.967 -78.232) (xy 116.967 -77.724)
				)
			)
		)
		(zone
			(layer "B.Cu")
			(hatch none 0.5)
			(connect_pads
				(clearance 0)
			)
			(min_thickness 0.25)
			(keepout
				(tracks allowed)
				(vias not_allowed)
				(pads allowed)
				(copperpour not_allowed)
				(footprints allowed)
			)
			(placement
				(enabled no)
				(sheetname "")
			)
			(fill
				(thermal_gap 0.5)
				(thermal_bridge_width 0.5)
				(island_removal_mode 0)
			)
			(polygon
				(pts
					(xy 116.967 -77.724) (xy 116.967 -78.232) (xy 116.586 -78.232) (xy 116.586 -77.724)
				)
			)
		)
	)
)
